# S9S_MB_2U (Grand Teton) — schematic netlist excerpt (pin names and nets, part order shuffled) for the footprints in the layout excerpt that follows; sources: Cadence DE-HDL packaged netlist, KiCad conversion of 03242023_DA0F0TMBIJ0_F0T_Motherboard_J_brd_V01_OCP.brd

C2010  Q_CAP  0.1UF 25V 10% X7R  pkg 0402  page 170 : A = P3V3_AUX ; B = GND
C905  Q_CAP_DIFFBUS  DIFF BUS_0.22UF 6.3V 20% X6S  pkg C0201  page 173 : \1\ = P5E_CPU0_PE0_TX_C_DP<14> ; \2\ = P5E_CPU0_PE0_TX_DP<14>
R4541  Q_RES  33.2 1% CHIP  pkg 0402LF  page 237 : A = SMB_HOST_CLK_BUF_ISO_3V3AUX_S_2 ; B = SMB_HOST_CLK_BUF_ISO_3V3AUX_SDA

(kicad_pcb
	(version 20260206)
	(generator "pcbnew")
	(generator_version "10.0")
	(general
		(thickness 1.6)
		(legacy_teardrops no)
	)
	(paper "A4")
	(title_block
		(title "03242023_DA0F0TMBIJ0_F0T_Motherboard_J_brd_V01_OCP.brd")
		(comment 1 "Grand Teton / footprints 481-483 of 6105")
	)
	(layers
		(0 "F.Cu" signal "TOP")
		(4 "In1.Cu" signal "GND")
		(6 "In2.Cu" signal "IN1")
		(8 "In3.Cu" signal "GND1")
		(10 "In4.Cu" signal "IN2")
		(12 "In5.Cu" signal "GND2")
		(14 "In6.Cu" signal "IN3")
		(16 "In7.Cu" signal "GND3")
		(18 "In8.Cu" signal "VCC")
		(20 "In9.Cu" signal "VCC1")
		(22 "In10.Cu" signal "GND4")
		(24 "In11.Cu" signal "IN4")
		(26 "In12.Cu" signal "GND5")
		(28 "In13.Cu" signal "IN5")
		(30 "In14.Cu" signal "GND6")
		(32 "In15.Cu" signal "IN6")
		(34 "In16.Cu" signal "GND7")
		(2 "B.Cu" signal "BOTTOM")
		(9 "F.Adhes" user "F.Adhesive")
		(11 "B.Adhes" user "B.Adhesive")
		(13 "F.Paste" user "Package Geometry/Pastemask Top")
		(15 "B.Paste" user "Package Geometry/Pastemask Bottom")
		(5 "F.SilkS" user "Ref Des/Silkscreen Top")
		(7 "B.SilkS" user "Ref Des/Silkscreen Bottom")
		(1 "F.Mask" user "Board Geometry/Soldermask Top")
		(3 "B.Mask" user "Board Geometry/Soldermask Bottom")
		(17 "Dwgs.User" user "User.Drawings")
		(19 "Cmts.User" user "User.Comments")
		(21 "Eco1.User" user "User.Eco1")
		(23 "Eco2.User" user "User.Eco2")
		(25 "Edge.Cuts" user "Board Geometry/Outline")
		(27 "Margin" user)
		(31 "F.CrtYd" user "Package Geometry/Place Bound Top")
		(29 "B.CrtYd" user "Package Geometry/Place Bound Bottom")
		(35 "F.Fab" user "Ref Des/Assembly Top")
		(33 "B.Fab" user "Ref Des/Assembly Bottom")
	)
	(footprint ""
		(layer "F.Cu")
		(at 309.278528 -408.517344 -90)
		(property "Reference" "C905"
			(at 0 0 270)
			(layer "F.SilkS")
			(hide yes)
			(effects
				(font
					(size 1.27 1.27)
				)
			)
		)
		(property "Value" ""
			(at 0 0 270)
			(layer "F.Fab")
			(effects
				(font
					(size 1.27 1.27)
				)
			)
		)
		(duplicate_pad_numbers_are_jumpers no)
		(fp_line
			(start -0.299974 0.150114)
			(end -0.299974 -0.150114)
			(stroke
				(width 0.1)
				(type default)
			)
			(layer "F.Fab")
		)
		(fp_line
			(start 0.299974 0.150114)
			(end -0.299974 0.150114)
			(stroke
				(width 0.1)
				(type default)
			)
			(layer "F.Fab")
		)
		(fp_line
			(start -0.299974 -0.150114)
			(end 0.299974 -0.150114)
			(stroke
				(width 0.1)
				(type default)
			)
			(layer "F.Fab")
		)
		(fp_line
			(start 0.299974 -0.150114)
			(end 0.299974 0.150114)
			(stroke
				(width 0.1)
				(type default)
			)
			(layer "F.Fab")
		)
		(pad "1" smd rect
			(at -0.2667 0 270)
			(size 0.3048 0.381)
			(layers "F.Cu" "F.Mask" "F.Paste")
			(net "P5E_CPU0_PE0_TX_C_DP<14>")
		)
		(pad "2" smd rect
			(at 0.2667 0 270)
			(size 0.3048 0.381)
			(layers "F.Cu" "F.Mask" "F.Paste")
			(net "P5E_CPU0_PE0_TX_DP<14>")
		)
	)
	(footprint ""
		(layer "F.Cu")
		(at 374.275858 -421.525446 -90)
		(property "Reference" "C2010"
			(at 0 0 270)
			(layer "F.SilkS")
			(hide yes)
			(effects
				(font
					(size 1.27 1.27)
				)
			)
		)
		(property "Value" ""
			(at 0 0 270)
			(layer "F.Fab")
			(effects
				(font
					(size 1.27 1.27)
				)
			)
		)
		(duplicate_pad_numbers_are_jumpers no)
		(fp_line
			(start -0.7874 0.4064)
			(end -0.7874 -0.4064)
			(stroke
				(width 0.1524)
				(type default)
			)
			(layer "F.SilkS")
		)
		(fp_line
			(start 0.7874 0.4064)
			(end -0.7874 0.4064)
			(stroke
				(width 0.1524)
				(type default)
			)
			(layer "F.SilkS")
		)
		(fp_line
			(start -0.7874 -0.4064)
			(end 0.7874 -0.4064)
			(stroke
				(width 0.1524)
				(type default)
			)
			(layer "F.SilkS")
		)
		(fp_line
			(start 0.7874 -0.4064)
			(end 0.7874 0.4064)
			(stroke
				(width 0.1524)
				(type default)
			)
			(layer "F.SilkS")
		)
		(fp_line
			(start -0.67945 0.3048)
			(end -0.67945 -0.305054)
			(stroke
				(width 0.1)
				(type default)
			)
			(layer "F.Fab")
		)
		(fp_line
			(start -0.12065 0.3048)
			(end -0.67945 0.3048)
			(stroke
				(width 0.1)
				(type default)
			)
			(layer "F.Fab")
		)
		(fp_line
			(start 0.120396 0.3048)
			(end 0.120396 0.2794)
			(stroke
				(width 0.1)
				(type default)
			)
			(layer "F.Fab")
		)
		(fp_line
			(start 0.67945 0.3048)
			(end 0.120396 0.3048)
			(stroke
				(width 0.1)
				(type default)
			)
			(layer "F.Fab")
		)
		(fp_line
			(start -0.12065 0.2794)
			(end -0.12065 0.3048)
			(stroke
				(width 0.1)
				(type default)
			)
			(layer "F.Fab")
		)
		(fp_line
			(start 0.120396 0.2794)
			(end -0.12065 0.2794)
			(stroke
				(width 0.1)
				(type default)
			)
			(layer "F.Fab")
		)
		(fp_line
			(start -0.12065 -0.2794)
			(end 0.12065 -0.2794)
			(stroke
				(width 0.1)
				(type default)
			)
			(layer "F.Fab")
		)
		(fp_line
			(start 0.12065 -0.2794)
			(end 0.12065 -0.3048)
			(stroke
				(width 0.1)
				(type default)
			)
			(layer "F.Fab")
		)
		(fp_line
			(start 0.12065 -0.3048)
			(end 0.67945 -0.3048)
			(stroke
				(width 0.1)
				(type default)
			)
			(layer "F.Fab")
		)
		(fp_line
			(start 0.67945 -0.3048)
			(end 0.67945 0.3048)
			(stroke
				(width 0.1)
				(type default)
			)
			(layer "F.Fab")
		)
		(fp_line
			(start -0.67945 -0.305054)
			(end -0.12065 -0.305054)
			(stroke
				(width 0.1)
				(type default)
			)
			(layer "F.Fab")
		)
		(fp_line
			(start -0.12065 -0.305054)
			(end -0.12065 -0.2794)
			(stroke
				(width 0.1)
				(type default)
			)
			(layer "F.Fab")
		)
		(pad "1" smd circle
			(at -0.40005 0 270)
			(size 0 0)
			(layers "F.Cu" "F.Mask" "F.Paste")
			(net "P3V3_AUX")
		)
		(pad "2" smd circle
			(at 0.40005 0 270)
			(size 0 0)
			(layers "F.Cu" "F.Mask" "F.Paste")
			(net "GND")
		)
	)
	(footprint ""
		(layer "F.Cu")
		(at 263.55294 -133.005068 180)
		(property "Reference" "R4541"
			(at 0 0 180)
			(layer "F.SilkS")
			(hide yes)
			(effects
				(font
					(size 1.27 1.27)
				)
			)
		)
		(property "Value" ""
			(at 0 0 180)
			(layer "F.Fab")
			(effects
				(font
					(size 1.27 1.27)
				)
			)
		)
		(duplicate_pad_numbers_are_jumpers no)
		(fp_line
			(start 0.7874 0.4064)
			(end -0.7874 0.4064)
			(stroke
				(width 0.1524)
				(type default)
			)
			(layer "F.SilkS")
		)
		(fp_line
			(start 0.7874 -0.4064)
			(end 0.7874 0.4064)
			(stroke
				(width 0.1524)
				(type default)
			)
			(layer "F.SilkS")
		)
		(fp_line
			(start -0.7874 0.4064)
			(end -0.7874 -0.4064)
			(stroke
				(width 0.1524)
				(type default)
			)
			(layer "F.SilkS")
		)
		(fp_line
			(start -0.7874 -0.4064)
			(end 0.7874 -0.4064)
			(stroke
				(width 0.1524)
				(type default)
			)
			(layer "F.SilkS")
		)
		(fp_line
			(start 0.67945 0.3048)
			(end 0.120396 0.3048)
			(stroke
				(width 0.1)
				(type default)
			)
			(layer "F.Fab")
		)
		(fp_line
			(start 0.67945 -0.3048)
			(end 0.67945 0.3048)
			(stroke
				(width 0.1)
				(type default)
			)
			(layer "F.Fab")
		)
		(fp_line
			(start 0.12065 -0.2794)
			(end 0.12065 -0.3048)
			(stroke
				(width 0.1)
				(type default)
			)
			(layer "F.Fab")
		)
		(fp_line
			(start 0.12065 -0.3048)
			(end 0.67945 -0.3048)
			(stroke
				(width 0.1)
				(type default)
			)
			(layer "F.Fab")
		)
		(fp_line
			(start 0.120396 0.3048)
			(end 0.120396 0.2794)
			(stroke
				(width 0.1)
				(type default)
			)
			(layer "F.Fab")
		)
		(fp_line
			(start 0.120396 0.2794)
			(end -0.12065 0.2794)
			(stroke
				(width 0.1)
				(type default)
			)
			(layer "F.Fab")
		)
		(fp_line
			(start -0.12065 0.3048)
			(end -0.67945 0.3048)
			(stroke
				(width 0.1)
				(type default)
			)
			(layer "F.Fab")
		)
		(fp_line
			(start -0.12065 0.2794)
			(end -0.12065 0.3048)
			(stroke
				(width 0.1)
				(type default)
			)
			(layer "F.Fab")
		)
		(fp_line
			(start -0.12065 -0.2794)
			(end 0.12065 -0.2794)
			(stroke
				(width 0.1)
				(type default)
			)
			(layer "F.Fab")
		)
		(fp_line
			(start -0.12065 -0.305054)
			(end -0.12065 -0.2794)
			(stroke
				(width 0.1)
				(type default)
			)
			(layer "F.Fab")
		)
		(fp_line
			(start -0.67945 0.3048)
			(end -0.67945 -0.305054)
			(stroke
				(width 0.1)
				(type default)
			)
			(layer "F.Fab")
		)
		(fp_line
			(start -0.67945 -0.305054)
			(end -0.12065 -0.305054)
			(stroke
				(width 0.1)
				(type default)
			)
			(layer "F.Fab")
		)
		(pad "1" smd circle
			(at -0.40005 0 180)
			(size 0 0)
			(layers "F.Cu" "F.Mask" "F.Paste")
			(net "SMB_HOST_CLK_BUF_ISO_3V3AUX_S_2")
		)
		(pad "2" smd circle
			(at 0.40005 0 180)
			(size 0 0)
			(layers "F.Cu" "F.Mask" "F.Paste")
			(net "SMB_HOST_CLK_BUF_ISO_3V3AUX_SDA")
		)
	)
)
